(kicad_pcb
	(version 20260206)
	(generator "pcbnew")
	(generator_version "10.0")
	(general
		(thickness 1.6)
		(legacy_teardrops no)
	)
	(paper "A4")
	(title_block
		(title "04192023_DAF0TMB3IC0_F0TG_MB_C_brd_V02_OCP.brd")
		(comment 1 "Grand Teton / footprints 2930-2935 of 8354")
	)
	(layers
		(0 "F.Cu" signal "TOP")
		(4 "In1.Cu" signal "GND")
		(6 "In2.Cu" signal "IN1")
		(8 "In3.Cu" signal "GND1")
		(10 "In4.Cu" signal "IN2")
		(12 "In5.Cu" signal "GND2")
		(14 "In6.Cu" signal "IN3")
		(16 "In7.Cu" signal "GND3")
		(18 "In8.Cu" signal "VCC")
		(20 "In9.Cu" signal "VCC1")
		(22 "In10.Cu" signal "GND4")
		(24 "In11.Cu" signal "IN4")
		(26 "In12.Cu" signal "GND5")
		(28 "In13.Cu" signal "IN5")
		(30 "In14.Cu" signal "GND6")
		(32 "In15.Cu" signal "IN6")
		(34 "In16.Cu" signal "GND7")
		(2 "B.Cu" signal "BOTTOM")
		(9 "F.Adhes" user "F.Adhesive")
		(11 "B.Adhes" user "B.Adhesive")
		(13 "F.Paste" user "Package Geometry/Pastemask Top")
		(15 "B.Paste" user "Package Geometry/Pastemask Bottom")
		(5 "F.SilkS" user "Ref Des/Silkscreen Top")
		(7 "B.SilkS" user "Ref Des/Silkscreen Bottom")
		(1 "F.Mask" user "Board Geometry/Soldermask Top")
		(3 "B.Mask" user "Board Geometry/Soldermask Bottom")
		(17 "Dwgs.User" user "User.Drawings")
		(19 "Cmts.User" user "User.Comments")
		(21 "Eco1.User" user "User.Eco1")
		(23 "Eco2.User" user "User.Eco2")
		(25 "Edge.Cuts" user "Board Geometry/Outline")
		(27 "Margin" user)
		(31 "F.CrtYd" user "Package Geometry/Place Bound Top")
		(29 "B.CrtYd" user "Package Geometry/Place Bound Bottom")
		(35 "F.Fab" user "Ref Des/Assembly Top")
		(33 "B.Fab" user "Ref Des/Assembly Bottom")
	)
	(footprint ""
		(layer "F.Cu")
		(at 83.222084 -38.63848 180)
		(property "Reference" "R6059"
			(at 0 0 180)
			(layer "F.SilkS")
			(hide yes)
			(effects
				(font
					(size 1.27 1.27)
				)
			)
		)
		(property "Value" ""
			(at 0 0 180)
			(layer "F.Fab")
			(effects
				(font
					(size 1.27 1.27)
				)
			)
		)
		(duplicate_pad_numbers_are_jumpers no)
		(fp_line
			(start 0.7874 0.4064)
			(end -0.7874 0.4064)
			(stroke
				(width 0.1524)
				(type default)
			)
			(layer "F.SilkS")
		)
		(fp_line
			(start 0.7874 -0.4064)
			(end 0.7874 0.4064)
			(stroke
				(width 0.1524)
				(type default)
			)
			(layer "F.SilkS")
		)
		(fp_line
			(start -0.7874 0.4064)
			(end -0.7874 -0.4064)
			(stroke
				(width 0.1524)
				(type default)
			)
			(layer "F.SilkS")
		)
		(fp_line
			(start -0.7874 -0.4064)
			(end 0.7874 -0.4064)
			(stroke
				(width 0.1524)
				(type default)
			)
			(layer "F.SilkS")
		)
		(fp_line
			(start 0.67945 0.3048)
			(end 0.120396 0.3048)
			(stroke
				(width 0.1)
				(type default)
			)
			(layer "F.Fab")
		)
		(fp_line
			(start 0.67945 -0.3048)
			(end 0.67945 0.3048)
			(stroke
				(width 0.1)
				(type default)
			)
			(layer "F.Fab")
		)
		(fp_line
			(start 0.12065 -0.2794)
			(end 0.12065 -0.3048)
			(stroke
				(width 0.1)
				(type default)
			)
			(layer "F.Fab")
		)
		(fp_line
			(start 0.12065 -0.3048)
			(end 0.67945 -0.3048)
			(stroke
				(width 0.1)
				(type default)
			)
			(layer "F.Fab")
		)
		(fp_line
			(start 0.120396 0.3048)
			(end 0.120396 0.2794)
			(stroke
				(width 0.1)
				(type default)
			)
			(layer "F.Fab")
		)
		(fp_line
			(start 0.120396 0.2794)
			(end -0.12065 0.2794)
			(stroke
				(width 0.1)
				(type default)
			)
			(layer "F.Fab")
		)
		(fp_line
			(start -0.12065 0.3048)
			(end -0.67945 0.3048)
			(stroke
				(width 0.1)
				(type default)
			)
			(layer "F.Fab")
		)
		(fp_line
			(start -0.12065 0.2794)
			(end -0.12065 0.3048)
			(stroke
				(width 0.1)
				(type default)
			)
			(layer "F.Fab")
		)
		(fp_line
			(start -0.12065 -0.2794)
			(end 0.12065 -0.2794)
			(stroke
				(width 0.1)
				(type default)
			)
			(layer "F.Fab")
		)
		(fp_line
			(start -0.12065 -0.305054)
			(end -0.12065 -0.2794)
			(stroke
				(width 0.1)
				(type default)
			)
			(layer "F.Fab")
		)
		(fp_line
			(start -0.67945 0.3048)
			(end -0.67945 -0.305054)
			(stroke
				(width 0.1)
				(type default)
			)
			(layer "F.Fab")
		)
		(fp_line
			(start -0.67945 -0.305054)
			(end -0.12065 -0.305054)
			(stroke
				(width 0.1)
				(type default)
			)
			(layer "F.Fab")
		)
		(pad "1" smd circle
			(at -0.40005 0 180)
			(size 0 0)
			(layers "F.Cu" "F.Mask" "F.Paste")
			(net "RST_PERST_OCP_V3_2_BUF2_N")
		)
		(pad "2" smd circle
			(at 0.40005 0 180)
			(size 0 0)
			(layers "F.Cu" "F.Mask" "F.Paste")
			(net "RST_PERST3_OCP_V3_2_N")
		)
	)
	(footprint ""
		(layer "F.Cu")
		(at 69.341492 -171.932854)
		(property "Reference" "PC321"
			(at 0 0 0)
			(layer "F.SilkS")
			(hide yes)
			(effects
				(font
					(size 1.27 1.27)
				)
			)
		)
		(property "Value" ""
			(at 0 0 0)
			(layer "F.Fab")
			(effects
				(font
					(size 1.27 1.27)
				)
			)
		)
		(duplicate_pad_numbers_are_jumpers no)
		(fp_line
			(start -0.7874 -0.4064)
			(end 0.7874 -0.4064)
			(stroke
				(width 0.1524)
				(type default)
			)
			(layer "F.SilkS")
		)
		(fp_line
			(start -0.7874 0.4064)
			(end -0.7874 -0.4064)
			(stroke
				(width 0.1524)
				(type default)
			)
			(layer "F.SilkS")
		)
		(fp_line
			(start 0.7874 -0.4064)
			(end 0.7874 0.4064)
			(stroke
				(width 0.1524)
				(type default)
			)
			(layer "F.SilkS")
		)
		(fp_line
			(start 0.7874 0.4064)
			(end -0.7874 0.4064)
			(stroke
				(width 0.1524)
				(type default)
			)
			(layer "F.SilkS")
		)
		(fp_line
			(start -0.67945 -0.305054)
			(end -0.12065 -0.305054)
			(stroke
				(width 0.1)
				(type default)
			)
			(layer "F.Fab")
		)
		(fp_line
			(start -0.67945 0.3048)
			(end -0.67945 -0.305054)
			(stroke
				(width 0.1)
				(type default)
			)
			(layer "F.Fab")
		)
		(fp_line
			(start -0.12065 -0.305054)
			(end -0.12065 -0.2794)
			(stroke
				(width 0.1)
				(type default)
			)
			(layer "F.Fab")
		)
		(fp_line
			(start -0.12065 -0.2794)
			(end 0.12065 -0.2794)
			(stroke
				(width 0.1)
				(type default)
			)
			(layer "F.Fab")
		)
		(fp_line
			(start -0.12065 0.2794)
			(end -0.12065 0.3048)
			(stroke
				(width 0.1)
				(type default)
			)
			(layer "F.Fab")
		)
		(fp_line
			(start -0.12065 0.3048)
			(end -0.67945 0.3048)
			(stroke
				(width 0.1)
				(type default)
			)
			(layer "F.Fab")
		)
		(fp_line
			(start 0.120396 0.2794)
			(end -0.12065 0.2794)
			(stroke
				(width 0.1)
				(type default)
			)
			(layer "F.Fab")
		)
		(fp_line
			(start 0.120396 0.3048)
			(end 0.120396 0.2794)
			(stroke
				(width 0.1)
				(type default)
			)
			(layer "F.Fab")
		)
		(fp_line
			(start 0.12065 -0.3048)
			(end 0.67945 -0.3048)
			(stroke
				(width 0.1)
				(type default)
			)
			(layer "F.Fab")
		)
		(fp_line
			(start 0.12065 -0.2794)
			(end 0.12065 -0.3048)
			(stroke
				(width 0.1)
				(type default)
			)
			(layer "F.Fab")
		)
		(fp_line
			(start 0.67945 -0.3048)
			(end 0.67945 0.3048)
			(stroke
				(width 0.1)
				(type default)
			)
			(layer "F.Fab")
		)
		(fp_line
			(start 0.67945 0.3048)
			(end 0.120396 0.3048)
			(stroke
				(width 0.1)
				(type default)
			)
			(layer "F.Fab")
		)
		(pad "1" smd circle
			(at -0.40005 0)
			(size 0 0)
			(layers "F.Cu" "F.Mask" "F.Paste")
			(net "SW_PVDDCR_CPU0_P1_SW6")
		)
		(pad "2" smd circle
			(at 0.40005 0)
			(size 0 0)
			(layers "F.Cu" "F.Mask" "F.Paste")
			(net "SW_PVDDCR_CPU0_P1_SW6_RC")
		)
	)
	(footprint ""
		(layer "F.Cu")
		(at 438.996074 -360.606848)
		(property "Reference" "PL24"
			(at -2.3876 -2.969768 0)
			(unlocked yes)
			(layer "F.SilkS")
			(effects
				(font
					(size 0.7874 0.5842)
					(thickness 0.1524)
				)
				(justify left)
			)
		)
		(property "Value" ""
			(at 0 0 0)
			(layer "F.Fab")
			(effects
				(font
					(size 1.27 1.27)
				)
			)
		)
		(duplicate_pad_numbers_are_jumpers no)
		(fp_line
			(start -2.249932 -2.249932)
			(end 2.249932 -2.249932)
			(stroke
				(width 0.1524)
				(type default)
			)
			(layer "F.SilkS")
		)
		(fp_line
			(start -2.249932 -1.3843)
			(end -2.249932 -2.249932)
			(stroke
				(width 0.1524)
				(type default)
			)
			(layer "F.SilkS")
		)
		(fp_line
			(start -2.249932 2.249932)
			(end -2.249932 1.3843)
			(stroke
				(width 0.1524)
				(type default)
			)
			(layer "F.SilkS")
		)
		(fp_line
			(start 2.249932 -2.249932)
			(end 2.249932 -1.3843)
			(stroke
				(width 0.1524)
				(type default)
			)
			(layer "F.SilkS")
		)
		(fp_line
			(start 2.249932 1.3843)
			(end 2.249932 2.249932)
			(stroke
				(width 0.1524)
				(type default)
			)
			(layer "F.SilkS")
		)
		(fp_line
			(start 2.249932 2.249932)
			(end -2.249932 2.249932)
			(stroke
				(width 0.1524)
				(type default)
			)
			(layer "F.SilkS")
		)
		(fp_line
			(start -2.249932 -2.249932)
			(end 2.249932 -2.249932)
			(stroke
				(width 0.1)
				(type default)
			)
			(layer "F.Fab")
		)
		(fp_line
			(start -2.249932 2.249932)
			(end -2.249932 -2.249932)
			(stroke
				(width 0.1)
				(type default)
			)
			(layer "F.Fab")
		)
		(fp_line
			(start 2.249932 -2.249932)
			(end 2.249932 2.249932)
			(stroke
				(width 0.1)
				(type default)
			)
			(layer "F.Fab")
		)
		(fp_line
			(start 2.249932 2.249932)
			(end -2.249932 2.249932)
			(stroke
				(width 0.1)
				(type default)
			)
			(layer "F.Fab")
		)
		(pad "1" smd rect
			(at -1.82499 0)
			(size 1.0668 2.5146)
			(layers "F.Cu" "F.Mask" "F.Paste")
			(net "SW_P12V_AUX_PVDD11_S3_P0_FLT")
		)
		(pad "2" smd rect
			(at 1.82499 0)
			(size 1.0668 2.5146)
			(layers "F.Cu" "F.Mask" "F.Paste")
			(net "P12V_AUX")
		)
	)
	(footprint ""
		(layer "F.Cu")
		(at 402.487638 -168.510966 90)
		(property "Reference" "PC584_2"
			(at 0 0 90)
			(layer "F.SilkS")
			(hide yes)
			(effects
				(font
					(size 1.27 1.27)
				)
			)
		)
		(property "Value" ""
			(at 0 0 90)
			(layer "F.Fab")
			(effects
				(font
					(size 1.27 1.27)
				)
			)
		)
		(duplicate_pad_numbers_are_jumpers no)
		(fp_line
			(start 0.7874 -0.4064)
			(end 0.7874 0.4064)
			(stroke
				(width 0.1524)
				(type default)
			)
			(layer "F.SilkS")
		)
		(fp_line
			(start -0.7874 -0.4064)
			(end 0.7874 -0.4064)
			(stroke
				(width 0.1524)
				(type default)
			)
			(layer "F.SilkS")
		)
		(fp_line
			(start 0.7874 0.4064)
			(end -0.7874 0.4064)
			(stroke
				(width 0.1524)
				(type default)
			)
			(layer "F.SilkS")
		)
		(fp_line
			(start -0.7874 0.4064)
			(end -0.7874 -0.4064)
			(stroke
				(width 0.1524)
				(type default)
			)
			(layer "F.SilkS")
		)
		(fp_line
			(start -0.12065 -0.305054)
			(end -0.12065 -0.2794)
			(stroke
				(width 0.1)
				(type default)
			)
			(layer "F.Fab")
		)
		(fp_line
			(start -0.67945 -0.305054)
			(end -0.12065 -0.305054)
			(stroke
				(width 0.1)
				(type default)
			)
			(layer "F.Fab")
		)
		(fp_line
			(start 0.67945 -0.3048)
			(end 0.67945 0.3048)
			(stroke
				(width 0.1)
				(type default)
			)
			(layer "F.Fab")
		)
		(fp_line
			(start 0.12065 -0.3048)
			(end 0.67945 -0.3048)
			(stroke
				(width 0.1)
				(type default)
			)
			(layer "F.Fab")
		)
		(fp_line
			(start 0.12065 -0.2794)
			(end 0.12065 -0.3048)
			(stroke
				(width 0.1)
				(type default)
			)
			(layer "F.Fab")
		)
		(fp_line
			(start -0.12065 -0.2794)
			(end 0.12065 -0.2794)
			(stroke
				(width 0.1)
				(type default)
			)
			(layer "F.Fab")
		)
		(fp_line
			(start 0.120396 0.2794)
			(end -0.12065 0.2794)
			(stroke
				(width 0.1)
				(type default)
			)
			(layer "F.Fab")
		)
		(fp_line
			(start -0.12065 0.2794)
			(end -0.12065 0.3048)
			(stroke
				(width 0.1)
				(type default)
			)
			(layer "F.Fab")
		)
		(fp_line
			(start 0.67945 0.3048)
			(end 0.120396 0.3048)
			(stroke
				(width 0.1)
				(type default)
			)
			(layer "F.Fab")
		)
		(fp_line
			(start 0.120396 0.3048)
			(end 0.120396 0.2794)
			(stroke
				(width 0.1)
				(type default)
			)
			(layer "F.Fab")
		)
		(fp_line
			(start -0.12065 0.3048)
			(end -0.67945 0.3048)
			(stroke
				(width 0.1)
				(type default)
			)
			(layer "F.Fab")
		)
		(fp_line
			(start -0.67945 0.3048)
			(end -0.67945 -0.305054)
			(stroke
				(width 0.1)
				(type default)
			)
			(layer "F.Fab")
		)
		(pad "1" smd circle
			(at -0.40005 0 90)
			(size 0 0)
			(layers "F.Cu" "F.Mask" "F.Paste")
			(net "SW_P12V_AUX_PVDDCR_SOC_P0_FLT")
		)
		(pad "2" smd circle
			(at 0.40005 0 90)
			(size 0 0)
			(layers "F.Cu" "F.Mask" "F.Paste")
			(net "GND")
		)
	)
	(footprint ""
		(layer "F.Cu")
		(at 259.834126 -96.206056 180)
		(property "Reference" "R1633"
			(at 0 0 180)
			(layer "F.SilkS")
			(hide yes)
			(effects
				(font
					(size 1.27 1.27)
				)
			)
		)
		(property "Value" ""
			(at 0 0 180)
			(layer "F.Fab")
			(effects
				(font
					(size 1.27 1.27)
				)
			)
		)
		(duplicate_pad_numbers_are_jumpers no)
		(fp_line
			(start 0.7874 0.4064)
			(end -0.7874 0.4064)
			(stroke
				(width 0.1524)
				(type default)
			)
			(layer "F.SilkS")
		)
		(fp_line
			(start 0.7874 -0.4064)
			(end 0.7874 0.4064)
			(stroke
				(width 0.1524)
				(type default)
			)
			(layer "F.SilkS")
		)
		(fp_line
			(start -0.7874 0.4064)
			(end -0.7874 -0.4064)
			(stroke
				(width 0.1524)
				(type default)
			)
			(layer "F.SilkS")
		)
		(fp_line
			(start -0.7874 -0.4064)
			(end 0.7874 -0.4064)
			(stroke
				(width 0.1524)
				(type default)
			)
			(layer "F.SilkS")
		)
		(fp_line
			(start 0.67945 0.3048)
			(end 0.120396 0.3048)
			(stroke
				(width 0.1)
				(type default)
			)
			(layer "F.Fab")
		)
		(fp_line
			(start 0.67945 -0.3048)
			(end 0.67945 0.3048)
			(stroke
				(width 0.1)
				(type default)
			)
			(layer "F.Fab")
		)
		(fp_line
			(start 0.12065 -0.2794)
			(end 0.12065 -0.3048)
			(stroke
				(width 0.1)
				(type default)
			)
			(layer "F.Fab")
		)
		(fp_line
			(start 0.12065 -0.3048)
			(end 0.67945 -0.3048)
			(stroke
				(width 0.1)
				(type default)
			)
			(layer "F.Fab")
		)
		(fp_line
			(start 0.120396 0.3048)
			(end 0.120396 0.2794)
			(stroke
				(width 0.1)
				(type default)
			)
			(layer "F.Fab")
		)
		(fp_line
			(start 0.120396 0.2794)
			(end -0.12065 0.2794)
			(stroke
				(width 0.1)
				(type default)
			)
			(layer "F.Fab")
		)
		(fp_line
			(start -0.12065 0.3048)
			(end -0.67945 0.3048)
			(stroke
				(width 0.1)
				(type default)
			)
			(layer "F.Fab")
		)
		(fp_line
			(start -0.12065 0.2794)
			(end -0.12065 0.3048)
			(stroke
				(width 0.1)
				(type default)
			)
			(layer "F.Fab")
		)
		(fp_line
			(start -0.12065 -0.2794)
			(end 0.12065 -0.2794)
			(stroke
				(width 0.1)
				(type default)
			)
			(layer "F.Fab")
		)
		(fp_line
			(start -0.12065 -0.305054)
			(end -0.12065 -0.2794)
			(stroke
				(width 0.1)
				(type default)
			)
			(layer "F.Fab")
		)
		(fp_line
			(start -0.67945 0.3048)
			(end -0.67945 -0.305054)
			(stroke
				(width 0.1)
				(type default)
			)
			(layer "F.Fab")
		)
		(fp_line
			(start -0.67945 -0.305054)
			(end -0.12065 -0.305054)
			(stroke
				(width 0.1)
				(type default)
			)
			(layer "F.Fab")
		)
		(pad "1" smd circle
			(at -0.40005 0 180)
			(size 0 0)
			(layers "F.Cu" "F.Mask" "F.Paste")
			(net "JTAG_TCK_R")
		)
		(pad "2" smd circle
			(at 0.40005 0 180)
			(size 0 0)
			(layers "F.Cu" "F.Mask" "F.Paste")
			(net "JTAG_TCK")
		)
	)
	(footprint ""
		(layer "F.Cu")
		(at 54.010814 -159.399478 180)
		(property "Reference" "PC89"
			(at 2.781808 3.588512 0)
			(unlocked yes)
			(layer "F.SilkS")
			(effects
				(font
					(size 0.7874 0.5842)
					(thickness 0.1524)
				)
				(justify left)
			)
		)
		(property "Value" ""
			(at 0 0 180)
			(layer "F.Fab")
			(effects
				(font
					(size 1.27 1.27)
				)
			)
		)
		(duplicate_pad_numbers_are_jumpers no)
		(fp_line
			(start 2.750058 2.750058)
			(end 2.750058 0.9398)
			(stroke
				(width 0.1524)
				(type default)
			)
			(layer "F.SilkS")
		)
		(fp_line
			(start 2.750058 -0.9398)
			(end 2.750058 -2.750058)
			(stroke
				(width 0.1524)
				(type default)
			)
			(layer "F.SilkS")
		)
		(fp_line
			(start 2.750058 -2.750058)
			(end -1.988058 -2.750058)
			(stroke
				(width 0.1524)
				(type default)
			)
			(layer "F.SilkS")
		)
		(fp_line
			(start -1.988058 2.750058)
			(end 2.750058 2.750058)
			(stroke
				(width 0.1524)
				(type default)
			)
			(layer "F.SilkS")
		)
		(fp_line
			(start -1.988058 -2.750058)
			(end -2.750058 -1.988058)
			(stroke
				(width 0.1524)
				(type default)
			)
			(layer "F.SilkS")
		)
		(fp_line
			(start -2.750058 1.988058)
			(end -1.988058 2.750058)
			(stroke
				(width 0.1524)
				(type default)
			)
			(layer "F.SilkS")
		)
		(fp_line
			(start -2.750058 0.9398)
			(end -2.750058 1.988058)
			(stroke
				(width 0.1524)
				(type default)
			)
			(layer "F.SilkS")
		)
		(fp_line
			(start -2.750058 -1.988058)
			(end -2.750058 -0.9398)
			(stroke
				(width 0.1524)
				(type default)
			)
			(layer "F.SilkS")
		)
		(fp_line
			(start 2.750058 2.750058)
			(end 2.750058 -2.750058)
			(stroke
				(width 0.1)
				(type default)
			)
			(layer "F.Fab")
		)
		(fp_line
			(start 2.750058 -2.750058)
			(end -2.750058 -2.750058)
			(stroke
				(width 0.1)
				(type default)
			)
			(layer "F.Fab")
		)
		(fp_line
			(start -2.750058 2.750058)
			(end 2.750058 2.750058)
			(stroke
				(width 0.1)
				(type default)
			)
			(layer "F.Fab")
		)
		(fp_line
			(start -2.750058 -2.750058)
			(end -2.750058 2.750058)
			(stroke
				(width 0.1)
				(type default)
			)
			(layer "F.Fab")
		)
		(pad "1" smd rect
			(at -2.199894 0 270)
			(size 1.6002 3.0226)
			(layers "F.Cu" "F.Mask" "F.Paste")
			(net "PVDD18_S5_P1")
		)
		(pad "2" smd rect
			(at 2.199894 0 270)
			(size 1.6002 3.0226)
			(layers "F.Cu" "F.Mask" "F.Paste")
			(net "GND")
		)
	)
)
